(kicad_pcb
	(version 20260206)
	(generator "pcbnew")
	(generator_version "10.0")
	(general
		(thickness 1.6)
		(legacy_teardrops no)
	)
	(paper "A4")
	(title_block
		(title "Bryce Canyon_R.DPB_16317-1_OCP.brd")
		(comment 1 "Bryce Canyon / footprints 1839-1846 of 2099")
	)
	(layers
		(0 "F.Cu" signal "TOP")
		(4 "In1.Cu" signal "L2GND")
		(6 "In2.Cu" signal "L3")
		(8 "In3.Cu" signal "L4VCC")
		(10 "In4.Cu" signal "L5VCC")
		(12 "In5.Cu" signal "L6")
		(14 "In6.Cu" signal "L7GND")
		(2 "B.Cu" signal "BOTTOM")
		(9 "F.Adhes" user "F.Adhesive")
		(11 "B.Adhes" user "B.Adhesive")
		(13 "F.Paste" user "Package Geometry/Pastemask Top")
		(15 "B.Paste" user "Package Geometry/Pastemask Bottom")
		(5 "F.SilkS" user "Ref Des/Silkscreen Top")
		(7 "B.SilkS" user "Ref Des/Silkscreen Bottom")
		(1 "F.Mask" user "Board Geometry/Soldermask Top")
		(3 "B.Mask" user "Board Geometry/Soldermask Bottom")
		(17 "Dwgs.User" user "User.Drawings")
		(19 "Cmts.User" user "User.Comments")
		(21 "Eco1.User" user "User.Eco1")
		(23 "Eco2.User" user "User.Eco2")
		(25 "Edge.Cuts" user "Board Geometry/Outline")
		(27 "Margin" user)
		(31 "F.CrtYd" user "Package Geometry/Place Bound Top")
		(29 "B.CrtYd" user "Package Geometry/Place Bound Bottom")
		(35 "F.Fab" user "Ref Des/Assembly Top")
		(33 "B.Fab" user "Ref Des/Assembly Bottom")
	)
	(footprint ""
		(layer "F.Cu")
		(at 319.40246 -244.884194 90)
		(property "Reference" "VIA13"
			(at 0 0 90)
			(layer "F.SilkS")
			(hide yes)
			(effects
				(font
					(size 1.27 1.27)
				)
			)
		)
		(property "Value" "100OHM-8L-2D36MM-L18-GP"
			(at 3.8989 0.5715 90)
			(unlocked yes)
			(layer "F.Fab")
			(hide yes)
			(effects
				(font
					(size 1.016 1.016)
					(thickness 0.1524)
				)
			)
		)
		(property "Device Type" "VIA-PCIE-4P-414097"
			(at 3.8989 -0.9525 90)
			(unlocked yes)
			(layer "F.Fab")
			(hide yes)
			(effects
				(font
					(size 1.016 1.016)
					(thickness 0.1524)
				)
			)
		)
		(duplicate_pad_numbers_are_jumpers no)
		(fp_rect
			(start -2.0701 0.4826)
			(end 2.0701 -0.4826)
			(stroke
				(width 0)
				(type default)
			)
			(fill no)
			(layer "F.CrtYd")
		)
		(fp_rect
			(start -2.0701 0.4826)
			(end 2.0701 -0.4826)
			(stroke
				(width 0)
				(type default)
			)
			(fill no)
			(layer "F.Fab")
		)
		(pad "1" thru_hole circle
			(at -1.5875 0 90)
			(size 0.508 0.508)
			(drill 0.254)
			(layers "*.Cu" "*.Mask")
			(remove_unused_layers no)
			(net "GND")
			(clearance 0.2286)
			(thermal_gap 0.2286)
		)
		(pad "2" thru_hole circle
			(at -0.5715 0 90)
			(size 0.508 0.508)
			(drill 0.254)
			(layers "*.Cu" "*.Mask")
			(remove_unused_layers no)
			(net "PHY_SCC_B_TO_DRV_B_6_DP")
			(clearance 0.2286)
			(thermal_gap 0.2286)
		)
		(pad "3" thru_hole circle
			(at 0.5715 0 90)
			(size 0.508 0.508)
			(drill 0.254)
			(layers "*.Cu" "*.Mask")
			(remove_unused_layers no)
			(net "PHY_SCC_B_TO_DRV_B_6_DN")
			(clearance 0.2286)
			(thermal_gap 0.2286)
		)
		(pad "4" thru_hole circle
			(at 1.5875 0 90)
			(size 0.508 0.508)
			(drill 0.254)
			(layers "*.Cu" "*.Mask")
			(remove_unused_layers no)
			(net "GND")
			(clearance 0.2286)
			(thermal_gap 0.2286)
		)
	)
	(footprint ""
		(layer "F.Cu")
		(at 221.522798 -107.414568)
		(property "Reference" "R16"
			(at 0 0 0)
			(layer "F.SilkS")
			(hide yes)
			(effects
				(font
					(size 1.27 1.27)
				)
			)
		)
		(property "Value" "1KR2F-3-GP"
			(at 0.064008 -3.993896 0)
			(unlocked yes)
			(layer "F.Fab")
			(hide yes)
			(effects
				(font
					(size 1.016 1.016)
					(thickness 0.1524)
				)
			)
		)
		(property "Device Type" "R402H16"
			(at 0.064008 -5.517896 0)
			(unlocked yes)
			(layer "F.Fab")
			(hide yes)
			(effects
				(font
					(size 1.016 1.016)
					(thickness 0.1524)
				)
			)
		)
		(duplicate_pad_numbers_are_jumpers no)
		(fp_line
			(start -0.508 -0.9398)
			(end -0.508 0.9398)
			(stroke
				(width 0.1524)
				(type default)
			)
			(layer "F.SilkS")
		)
		(fp_line
			(start 0.508 -0.9398)
			(end -0.508 -0.9398)
			(stroke
				(width 0.1524)
				(type default)
			)
			(layer "F.SilkS")
		)
		(fp_rect
			(start -0.508 0.9398)
			(end 0.508 -0.9398)
			(stroke
				(width 0)
				(type default)
			)
			(fill no)
			(layer "F.CrtYd")
		)
		(fp_rect
			(start -0.508 0.9398)
			(end 0.508 -0.9398)
			(stroke
				(width 0)
				(type default)
			)
			(fill no)
			(layer "F.Fab")
		)
		(pad "1" smd custom
			(at 0 -0.4445)
			(size 0.1397 0.1397)
			(layers "F.Cu" "F.Mask" "F.Paste")
			(net "P3V3_STBY_B")
			(options
				(clearance outline)
				(anchor circle)
			)
			(primitives
				(gr_poly
					(pts
						(arc
							(start -0.1778 -0.2794)
							(mid -0.249642 -0.249642)
							(end -0.2794 -0.1778)
						)
						(arc
							(start -0.2794 0.1778)
							(mid -0.249642 0.249642)
							(end -0.1778 0.2794)
						)
						(arc
							(start 0.1778 0.2794)
							(mid 0.249642 0.249642)
							(end 0.2794 0.1778)
						)
						(arc
							(start 0.2794 -0.1778)
							(mid 0.249642 -0.249642)
							(end 0.1778 -0.2794)
						)
					)
					(width 0)
					(fill yes)
				)
			)
		)
		(pad "2" smd custom
			(at 0 0.4445)
			(size 0.1397 0.1397)
			(layers "F.Cu" "F.Mask" "F.Paste")
			(net "I2C_BMC_B_EXP_B_SCL")
			(options
				(clearance outline)
				(anchor circle)
			)
			(primitives
				(gr_poly
					(pts
						(arc
							(start -0.1778 -0.2794)
							(mid -0.249642 -0.249642)
							(end -0.2794 -0.1778)
						)
						(arc
							(start -0.2794 0.1778)
							(mid -0.249642 0.249642)
							(end -0.1778 0.2794)
						)
						(arc
							(start 0.1778 0.2794)
							(mid 0.249642 0.249642)
							(end 0.2794 0.1778)
						)
						(arc
							(start 0.2794 -0.1778)
							(mid 0.249642 -0.249642)
							(end 0.1778 -0.2794)
						)
					)
					(width 0)
					(fill yes)
				)
			)
		)
	)
	(footprint ""
		(layer "F.Cu")
		(at 392.938 -267.843 180)
		(property "Reference" "C134"
			(at 0 0 180)
			(layer "F.SilkS")
			(hide yes)
			(effects
				(font
					(size 1.27 1.27)
				)
			)
		)
		(property "Value" "SC1U16V3KX-5GP"
			(at 0 -2.8194 180)
			(unlocked yes)
			(layer "F.Fab")
			(hide yes)
			(effects
				(font
					(size 1.016 1.016)
					(thickness 0.1524)
				)
			)
		)
		(property "Device Type" "C603H36"
			(at 0 -4.3434 180)
			(unlocked yes)
			(layer "F.Fab")
			(hide yes)
			(effects
				(font
					(size 1.016 1.016)
					(thickness 0.1524)
				)
			)
		)
		(duplicate_pad_numbers_are_jumpers no)
		(fp_line
			(start 0.508 0)
			(end -0.508 0)
			(stroke
				(width 0.2032)
				(type default)
			)
			(layer "F.SilkS")
		)
		(fp_rect
			(start -0.5842 1.3335)
			(end 0.5842 -1.3335)
			(stroke
				(width 0)
				(type default)
			)
			(fill no)
			(layer "F.CrtYd")
		)
		(fp_rect
			(start -0.5842 1.3335)
			(end 0.5842 -1.3335)
			(stroke
				(width 0)
				(type default)
			)
			(fill no)
			(layer "F.Fab")
		)
		(pad "1" smd custom
			(at 0 -0.762 180)
			(size 0.2159 0.2159)
			(layers "F.Cu" "F.Mask" "F.Paste")
			(net "P5V_HDD8")
			(options
				(clearance outline)
				(anchor circle)
			)
			(primitives
				(gr_poly
					(pts
						(arc
							(start -0.3302 -0.4318)
							(mid -0.402042 -0.402042)
							(end -0.4318 -0.3302)
						)
						(arc
							(start -0.4318 0.3302)
							(mid -0.402042 0.402042)
							(end -0.3302 0.4318)
						)
						(arc
							(start 0.3302 0.4318)
							(mid 0.402042 0.402042)
							(end 0.4318 0.3302)
						)
						(arc
							(start 0.4318 -0.3302)
							(mid 0.402042 -0.402042)
							(end 0.3302 -0.4318)
						)
					)
					(width 0)
					(fill yes)
				)
			)
		)
		(pad "2" smd custom
			(at 0 0.762 180)
			(size 0.2159 0.2159)
			(layers "F.Cu" "F.Mask" "F.Paste")
			(net "GND")
			(options
				(clearance outline)
				(anchor circle)
			)
			(primitives
				(gr_poly
					(pts
						(arc
							(start -0.3302 -0.4318)
							(mid -0.402042 -0.402042)
							(end -0.4318 -0.3302)
						)
						(arc
							(start -0.4318 0.3302)
							(mid -0.402042 0.402042)
							(end -0.3302 0.4318)
						)
						(arc
							(start 0.3302 0.4318)
							(mid 0.402042 0.402042)
							(end 0.4318 0.3302)
						)
						(arc
							(start 0.4318 -0.3302)
							(mid 0.402042 -0.402042)
							(end 0.3302 -0.4318)
						)
					)
					(width 0)
					(fill yes)
				)
			)
		)
	)
	(footprint ""
		(layer "F.Cu")
		(at 353.184714 -244.660674 -90)
		(property "Reference" "C120"
			(at 0 0 270)
			(layer "F.SilkS")
			(hide yes)
			(effects
				(font
					(size 1.27 1.27)
				)
			)
		)
		(property "Value" "SCD01U16V1KX-GP"
			(at -2.8321 -1.7399 270)
			(unlocked yes)
			(layer "F.Fab")
			(hide yes)
			(effects
				(font
					(size 1.016 1.016)
					(thickness 0.1524)
				)
			)
		)
		(property "Device Type" "C0201H13"
			(at -2.8321 -3.2639 270)
			(unlocked yes)
			(layer "F.Fab")
			(hide yes)
			(effects
				(font
					(size 1.016 1.016)
					(thickness 0.1524)
				)
			)
		)
		(duplicate_pad_numbers_are_jumpers no)
		(fp_rect
			(start -0.2794 0.6477)
			(end 0.2794 -0.6477)
			(stroke
				(width 0)
				(type default)
			)
			(fill no)
			(layer "F.CrtYd")
		)
		(fp_rect
			(start -0.2794 0.6477)
			(end 0.2794 -0.6477)
			(stroke
				(width 0)
				(type default)
			)
			(fill no)
			(layer "F.Fab")
		)
		(pad "1" smd custom
			(at 0 -0.2794 270)
			(size 0.0762 0.0762)
			(layers "F.Cu" "F.Mask" "F.Paste")
			(net "SAS_HDD_RX_P7")
			(options
				(clearance outline)
				(anchor circle)
			)
			(primitives
				(gr_poly
					(pts
						(arc
							(start 0.1524 -0.127)
							(mid 0.137521 -0.162921)
							(end 0.1016 -0.1778)
						)
						(arc
							(start -0.1016 -0.1778)
							(mid -0.137521 -0.162921)
							(end -0.1524 -0.127)
						)
						(arc
							(start -0.1524 0.127)
							(mid -0.137521 0.162921)
							(end -0.1016 0.1778)
						)
						(arc
							(start 0.1016 0.1778)
							(mid 0.137521 0.162921)
							(end 0.1524 0.127)
						)
					)
					(width 0)
					(fill yes)
				)
			)
		)
		(pad "2" smd custom
			(at 0 0.2794 270)
			(size 0.0762 0.0762)
			(layers "F.Cu" "F.Mask" "F.Paste")
			(net "PHY_SCC_B_TO_DRV_B_7_DP")
			(options
				(clearance outline)
				(anchor circle)
			)
			(primitives
				(gr_poly
					(pts
						(arc
							(start 0.1524 -0.127)
							(mid 0.137521 -0.162921)
							(end 0.1016 -0.1778)
						)
						(arc
							(start -0.1016 -0.1778)
							(mid -0.137521 -0.162921)
							(end -0.1524 -0.127)
						)
						(arc
							(start -0.1524 0.127)
							(mid -0.137521 0.162921)
							(end -0.1016 0.1778)
						)
						(arc
							(start 0.1016 0.1778)
							(mid 0.137521 0.162921)
							(end 0.1524 0.127)
						)
					)
					(width 0)
					(fill yes)
				)
			)
		)
	)
	(footprint ""
		(layer "F.Cu")
		(at 113.03 -99.314)
		(property "Reference" "R413"
			(at 0 0 0)
			(layer "F.SilkS")
			(hide yes)
			(effects
				(font
					(size 1.27 1.27)
				)
			)
		)
		(property "Value" "91R3F-1-GP"
			(at -0.0254 -2.5146 0)
			(unlocked yes)
			(layer "F.Fab")
			(hide yes)
			(effects
				(font
					(size 1.016 1.016)
					(thickness 0.1524)
				)
			)
		)
		(property "Device Type" "R603H22"
			(at -0.0254 -4.0386 0)
			(unlocked yes)
			(layer "F.Fab")
			(hide yes)
			(effects
				(font
					(size 1.016 1.016)
					(thickness 0.1524)
				)
			)
		)
		(duplicate_pad_numbers_are_jumpers no)
		(fp_line
			(start -0.4826 0)
			(end -0.2032 0)
			(stroke
				(width 0.2032)
				(type default)
			)
			(layer "F.SilkS")
		)
		(fp_line
			(start 0.2032 0)
			(end 0.4826 0)
			(stroke
				(width 0.2032)
				(type default)
			)
			(layer "F.SilkS")
		)
		(fp_rect
			(start -0.5842 1.3335)
			(end 0.5842 -1.3335)
			(stroke
				(width 0)
				(type default)
			)
			(fill no)
			(layer "F.CrtYd")
		)
		(fp_rect
			(start -0.5842 1.3335)
			(end 0.5842 -1.3335)
			(stroke
				(width 0)
				(type default)
			)
			(fill no)
			(layer "F.Fab")
		)
		(pad "1" smd custom
			(at 0 -0.762)
			(size 0.2159 0.2159)
			(layers "F.Cu" "F.Mask" "F.Paste")
			(net "P5V_B_2")
			(options
				(clearance outline)
				(anchor circle)
			)
			(primitives
				(gr_poly
					(pts
						(arc
							(start -0.3302 -0.4318)
							(mid -0.402042 -0.402042)
							(end -0.4318 -0.3302)
						)
						(arc
							(start -0.4318 0.3302)
							(mid -0.402042 0.402042)
							(end -0.3302 0.4318)
						)
						(arc
							(start 0.3302 0.4318)
							(mid 0.402042 0.402042)
							(end 0.4318 0.3302)
						)
						(arc
							(start 0.4318 -0.3302)
							(mid 0.402042 -0.402042)
							(end 0.3302 -0.4318)
						)
					)
					(width 0)
					(fill yes)
				)
			)
		)
		(pad "2" smd custom
			(at 0 0.762)
			(size 0.2159 0.2159)
			(layers "F.Cu" "F.Mask" "F.Paste")
			(net "DRV_ACT_15")
			(options
				(clearance outline)
				(anchor circle)
			)
			(primitives
				(gr_poly
					(pts
						(arc
							(start -0.3302 -0.4318)
							(mid -0.402042 -0.402042)
							(end -0.4318 -0.3302)
						)
						(arc
							(start -0.4318 0.3302)
							(mid -0.402042 0.402042)
							(end -0.3302 0.4318)
						)
						(arc
							(start 0.3302 0.4318)
							(mid 0.402042 0.402042)
							(end 0.4318 0.3302)
						)
						(arc
							(start 0.4318 -0.3302)
							(mid 0.402042 -0.402042)
							(end 0.3302 -0.4318)
						)
					)
					(width 0)
					(fill yes)
				)
			)
		)
	)
	(footprint ""
		(layer "F.Cu")
		(at 244.37848 -197.86854 -90)
		(property "Reference" "R73"
			(at 0 0 270)
			(layer "F.SilkS")
			(hide yes)
			(effects
				(font
					(size 1.27 1.27)
				)
			)
		)
		(property "Value" "4K7R2F-GP"
			(at 0.064008 -3.993896 270)
			(unlocked yes)
			(layer "F.Fab")
			(hide yes)
			(effects
				(font
					(size 1.016 1.016)
					(thickness 0.1524)
				)
			)
		)
		(property "Device Type" "R402H16"
			(at 0.064008 -5.517896 270)
			(unlocked yes)
			(layer "F.Fab")
			(hide yes)
			(effects
				(font
					(size 1.016 1.016)
					(thickness 0.1524)
				)
			)
		)
		(duplicate_pad_numbers_are_jumpers no)
		(fp_line
			(start -0.508 -0.9398)
			(end -0.508 0.9398)
			(stroke
				(width 0.1524)
				(type default)
			)
			(layer "F.SilkS")
		)
		(fp_line
			(start 0.508 -0.9398)
			(end -0.508 -0.9398)
			(stroke
				(width 0.1524)
				(type default)
			)
			(layer "F.SilkS")
		)
		(fp_rect
			(start -0.508 0.9398)
			(end 0.508 -0.9398)
			(stroke
				(width 0)
				(type default)
			)
			(fill no)
			(layer "F.CrtYd")
		)
		(fp_rect
			(start -0.508 0.9398)
			(end 0.508 -0.9398)
			(stroke
				(width 0)
				(type default)
			)
			(fill no)
			(layer "F.Fab")
		)
		(pad "1" smd custom
			(at 0 -0.4445 270)
			(size 0.1397 0.1397)
			(layers "F.Cu" "F.Mask" "F.Paste")
			(net "P3V3_STBY_B")
			(options
				(clearance outline)
				(anchor circle)
			)
			(primitives
				(gr_poly
					(pts
						(arc
							(start -0.1778 -0.2794)
							(mid -0.249642 -0.249642)
							(end -0.2794 -0.1778)
						)
						(arc
							(start -0.2794 0.1778)
							(mid -0.249642 0.249642)
							(end -0.1778 0.2794)
						)
						(arc
							(start 0.1778 0.2794)
							(mid 0.249642 0.249642)
							(end 0.2794 0.1778)
						)
						(arc
							(start 0.2794 -0.1778)
							(mid 0.249642 -0.249642)
							(end 0.1778 -0.2794)
						)
					)
					(width 0)
					(fill yes)
				)
			)
		)
		(pad "2" smd custom
			(at 0 0.4445 270)
			(size 0.1397 0.1397)
			(layers "F.Cu" "F.Mask" "F.Paste")
			(net "IO_EXP2_A2")
			(options
				(clearance outline)
				(anchor circle)
			)
			(primitives
				(gr_poly
					(pts
						(arc
							(start -0.1778 -0.2794)
							(mid -0.249642 -0.249642)
							(end -0.2794 -0.1778)
						)
						(arc
							(start -0.2794 0.1778)
							(mid -0.249642 0.249642)
							(end -0.1778 0.2794)
						)
						(arc
							(start 0.1778 0.2794)
							(mid 0.249642 0.249642)
							(end 0.2794 0.1778)
						)
						(arc
							(start 0.2794 -0.1778)
							(mid 0.249642 -0.249642)
							(end 0.1778 -0.2794)
						)
					)
					(width 0)
					(fill yes)
				)
			)
		)
	)
	(footprint ""
		(layer "F.Cu")
		(at 432.689 -250.444 90)
		(property "Reference" "R314"
			(at 0 0 90)
			(layer "F.SilkS")
			(hide yes)
			(effects
				(font
					(size 1.27 1.27)
				)
			)
		)
		(property "Value" "200KR2F-L-GP"
			(at 0.064008 -3.993896 90)
			(unlocked yes)
			(layer "F.Fab")
			(hide yes)
			(effects
				(font
					(size 1.016 1.016)
					(thickness 0.1524)
				)
			)
		)
		(property "Device Type" "R402H16"
			(at 0.064008 -5.517896 90)
			(unlocked yes)
			(layer "F.Fab")
			(hide yes)
			(effects
				(font
					(size 1.016 1.016)
					(thickness 0.1524)
				)
			)
		)
		(duplicate_pad_numbers_are_jumpers no)
		(fp_line
			(start 0.508 -0.9398)
			(end -0.508 -0.9398)
			(stroke
				(width 0.1524)
				(type default)
			)
			(layer "F.SilkS")
		)
		(fp_line
			(start -0.508 -0.9398)
			(end -0.508 0.9398)
			(stroke
				(width 0.1524)
				(type default)
			)
			(layer "F.SilkS")
		)
		(fp_rect
			(start -0.508 0.9398)
			(end 0.508 -0.9398)
			(stroke
				(width 0)
				(type default)
			)
			(fill no)
			(layer "F.CrtYd")
		)
		(fp_rect
			(start -0.508 0.9398)
			(end 0.508 -0.9398)
			(stroke
				(width 0)
				(type default)
			)
			(fill no)
			(layer "F.Fab")
		)
		(pad "1" smd custom
			(at 0 -0.4445 90)
			(size 0.1397 0.1397)
			(layers "F.Cu" "F.Mask" "F.Paste")
			(net "SW_HDD_R9")
			(options
				(clearance outline)
				(anchor circle)
			)
			(primitives
				(gr_poly
					(pts
						(arc
							(start -0.1778 -0.2794)
							(mid -0.249642 -0.249642)
							(end -0.2794 -0.1778)
						)
						(arc
							(start -0.2794 0.1778)
							(mid -0.249642 0.249642)
							(end -0.1778 0.2794)
						)
						(arc
							(start 0.1778 0.2794)
							(mid 0.249642 0.249642)
							(end 0.2794 0.1778)
						)
						(arc
							(start 0.2794 -0.1778)
							(mid 0.249642 -0.249642)
							(end 0.1778 -0.2794)
						)
					)
					(width 0)
					(fill yes)
				)
			)
		)
		(pad "2" smd custom
			(at 0 0.4445 90)
			(size 0.1397 0.1397)
			(layers "F.Cu" "F.Mask" "F.Paste")
			(net "SW_HDD_N9")
			(options
				(clearance outline)
				(anchor circle)
			)
			(primitives
				(gr_poly
					(pts
						(arc
							(start -0.1778 -0.2794)
							(mid -0.249642 -0.249642)
							(end -0.2794 -0.1778)
						)
						(arc
							(start -0.2794 0.1778)
							(mid -0.249642 0.249642)
							(end -0.1778 0.2794)
						)
						(arc
							(start 0.1778 0.2794)
							(mid 0.249642 0.249642)
							(end 0.2794 0.1778)
						)
						(arc
							(start 0.2794 -0.1778)
							(mid 0.249642 -0.249642)
							(end 0.1778 -0.2794)
						)
					)
					(width 0)
					(fill yes)
				)
			)
		)
	)
	(footprint ""
		(layer "F.Cu")
		(at 401.828 -143.891 90)
		(property "Reference" "C299"
			(at 0 0 90)
			(layer "F.SilkS")
			(hide yes)
			(effects
				(font
					(size 1.27 1.27)
				)
			)
		)
		(property "Value" "SCD033U25V2KX-GP"
			(at 1.1811 -2.7051 90)
			(unlocked yes)
			(layer "F.Fab")
			(hide yes)
			(effects
				(font
					(size 1.016 1.016)
					(thickness 0.1524)
				)
			)
		)
		(property "Device Type" "C402H22"
			(at 1.1811 -4.2291 90)
			(unlocked yes)
			(layer "F.Fab")
			(hide yes)
			(effects
				(font
					(size 1.016 1.016)
					(thickness 0.1524)
				)
			)
		)
		(duplicate_pad_numbers_are_jumpers no)
		(fp_rect
			(start -0.4318 0.9525)
			(end 0.4318 -0.9525)
			(stroke
				(width 0)
				(type default)
			)
			(fill no)
			(layer "F.CrtYd")
		)
		(fp_rect
			(start -0.4318 0.9525)
			(end 0.4318 -0.9525)
			(stroke
				(width 0)
				(type default)
			)
			(fill no)
			(layer "F.Fab")
		)
		(pad "1" smd custom
			(at 0 -0.4445 90)
			(size 0.1524 0.1524)
			(layers "F.Cu" "F.Mask" "F.Paste")
			(net "P12V_B")
			(options
				(clearance outline)
				(anchor circle)
			)
			(primitives
				(gr_poly
					(pts
						(arc
							(start 0.3048 -0.2032)
							(mid 0.275042 -0.275042)
							(end 0.2032 -0.3048)
						)
						(arc
							(start -0.2032 -0.3048)
							(mid -0.275042 -0.275042)
							(end -0.3048 -0.2032)
						)
						(arc
							(start -0.3048 0.2032)
							(mid -0.275042 0.275042)
							(end -0.2032 0.3048)
						)
						(arc
							(start 0.2032 0.3048)
							(mid 0.275042 0.275042)
							(end 0.3048 0.2032)
						)
					)
					(width 0)
					(fill yes)
				)
			)
		)
		(pad "2" smd custom
			(at 0 0.4445 90)
			(size 0.1524 0.1524)
			(layers "F.Cu" "F.Mask" "F.Paste")
			(net "SW_HDD_N20")
			(options
				(clearance outline)
				(anchor circle)
			)
			(primitives
				(gr_poly
					(pts
						(arc
							(start 0.3048 -0.2032)
							(mid 0.275042 -0.275042)
							(end 0.2032 -0.3048)
						)
						(arc
							(start -0.2032 -0.3048)
							(mid -0.275042 -0.275042)
							(end -0.3048 -0.2032)
						)
						(arc
							(start -0.3048 0.2032)
							(mid -0.275042 0.275042)
							(end -0.2032 0.3048)
						)
						(arc
							(start 0.2032 0.3048)
							(mid 0.275042 0.275042)
							(end 0.3048 0.2032)
						)
					)
					(width 0)
					(fill yes)
				)
			)
		)
	)
)
